# S9S_MB_2U (Grand Teton) — schematic netlist excerpt (pin names and nets, part order shuffled) for the footprints in the layout excerpt that follows; sources: Cadence DE-HDL packaged netlist, KiCad conversion of 03242023_DA0F0TMBIJ0_F0T_Motherboard_J_brd_V01_OCP.brd

U327  74CBTLV3126PW  IC  pkg TSSOP14  page 248
  \1oe\  = JTAG_BMC_SW_R_OE
  \1a\  = JTAG_BMC_TCK_R
  \1b\  = JTAG_BMC_SW_TCK_R
  \2oe\  = JTAG_BMC_SW_R_OE
  \2a\  = JTAG_BMC_TMS_R
  \2b\  = JTAG_BMC_SW_TMS_R
  GND  = GND
  \3b\  = JTAG_BMC_SW_TDI_R
  \3a\  = JTAG_BMC_TDI_R
  \3oe\  = JTAG_BMC_SW_R_OE
  \4b\  = JTAG_BMC_SW_TDO_R
  \4a\  = JTAG_BMC_TDO_R
  \4oe\  = JTAG_BMC_SW_R_OE
  VCC  = P3V3_AUX

H94  HOLE  EMPTY  pkg TH  page 311 : \1\ = GND

(kicad_pcb
	(version 20260206)
	(generator "pcbnew")
	(generator_version "10.0")
	(general
		(thickness 1.6)
		(legacy_teardrops no)
	)
	(paper "A4")
	(title_block
		(title "03242023_DA0F0TMBIJ0_F0T_Motherboard_J_brd_V01_OCP.brd")
		(comment 1 "Grand Teton / footprints 347-348 of 6105")
	)
	(layers
		(0 "F.Cu" signal "TOP")
		(4 "In1.Cu" signal "GND")
		(6 "In2.Cu" signal "IN1")
		(8 "In3.Cu" signal "GND1")
		(10 "In4.Cu" signal "IN2")
		(12 "In5.Cu" signal "GND2")
		(14 "In6.Cu" signal "IN3")
		(16 "In7.Cu" signal "GND3")
		(18 "In8.Cu" signal "VCC")
		(20 "In9.Cu" signal "VCC1")
		(22 "In10.Cu" signal "GND4")
		(24 "In11.Cu" signal "IN4")
		(26 "In12.Cu" signal "GND5")
		(28 "In13.Cu" signal "IN5")
		(30 "In14.Cu" signal "GND6")
		(32 "In15.Cu" signal "IN6")
		(34 "In16.Cu" signal "GND7")
		(2 "B.Cu" signal "BOTTOM")
		(9 "F.Adhes" user "F.Adhesive")
		(11 "B.Adhes" user "B.Adhesive")
		(13 "F.Paste" user "Package Geometry/Pastemask Top")
		(15 "B.Paste" user "Package Geometry/Pastemask Bottom")
		(5 "F.SilkS" user "Ref Des/Silkscreen Top")
		(7 "B.SilkS" user "Ref Des/Silkscreen Bottom")
		(1 "F.Mask" user "Board Geometry/Soldermask Top")
		(3 "B.Mask" user "Board Geometry/Soldermask Bottom")
		(17 "Dwgs.User" user "User.Drawings")
		(19 "Cmts.User" user "User.Comments")
		(21 "Eco1.User" user "User.Eco1")
		(23 "Eco2.User" user "User.Eco2")
		(25 "Edge.Cuts" user "Board Geometry/Outline")
		(27 "Margin" user)
		(31 "F.CrtYd" user "Package Geometry/Place Bound Top")
		(29 "B.CrtYd" user "Package Geometry/Place Bound Bottom")
		(35 "F.Fab" user "Ref Des/Assembly Top")
		(33 "B.Fab" user "Ref Des/Assembly Bottom")
	)
	(footprint ""
		(layer "F.Cu")
		(at 122.555 -55.971948)
		(property "Reference" "U327"
			(at 1.27 -3.52933 0)
			(unlocked yes)
			(layer "F.SilkS")
			(effects
				(font
					(size 0.7874 0.5842)
					(thickness 0.1524)
				)
				(justify left)
			)
		)
		(property "Value" ""
			(at 0 0 0)
			(layer "F.Fab")
			(effects
				(font
					(size 1.27 1.27)
				)
			)
		)
		(duplicate_pad_numbers_are_jumpers no)
		(fp_line
			(start -2.0066 -2.5527)
			(end -0.5715 -2.5527)
			(stroke
				(width 0.1524)
				(type default)
			)
			(layer "F.SilkS")
		)
		(fp_line
			(start -2.0066 2.5527)
			(end -2.0066 -2.5527)
			(stroke
				(width 0.1524)
				(type default)
			)
			(layer "F.SilkS")
		)
		(fp_line
			(start -0.5715 -2.5527)
			(end 0 -1.9812)
			(stroke
				(width 0.1524)
				(type default)
			)
			(layer "F.SilkS")
		)
		(fp_line
			(start 0 -1.9812)
			(end 0.5715 -2.5527)
			(stroke
				(width 0.1524)
				(type default)
			)
			(layer "F.SilkS")
		)
		(fp_line
			(start 0.5715 -2.5527)
			(end 2.0066 -2.5527)
			(stroke
				(width 0.1524)
				(type default)
			)
			(layer "F.SilkS")
		)
		(fp_line
			(start 2.0066 -2.5527)
			(end 2.0066 2.5527)
			(stroke
				(width 0.1524)
				(type default)
			)
			(layer "F.SilkS")
		)
		(fp_line
			(start 2.0066 2.5527)
			(end -2.0066 2.5527)
			(stroke
				(width 0.1524)
				(type default)
			)
			(layer "F.SilkS")
		)
		(fp_poly
			(pts
				(xy -4.36372 -1.608328) (xy -4.36372 -2.233168) (xy -3.81 -1.905)
			)
			(stroke
				(width 0)
				(type default)
			)
			(fill yes)
			(layer "F.SilkS")
		)
		(fp_line
			(start -2.249932 -2.549906)
			(end 2.249932 -2.549906)
			(stroke
				(width 0.1)
				(type default)
			)
			(layer "F.Fab")
		)
		(fp_line
			(start -2.249932 2.549906)
			(end -2.249932 -2.549906)
			(stroke
				(width 0.1)
				(type default)
			)
			(layer "F.Fab")
		)
		(fp_line
			(start 2.249932 -2.549906)
			(end 2.249932 2.549906)
			(stroke
				(width 0.1)
				(type default)
			)
			(layer "F.Fab")
		)
		(fp_line
			(start 2.249932 2.549906)
			(end -2.249932 2.549906)
			(stroke
				(width 0.1)
				(type default)
			)
			(layer "F.Fab")
		)
		(fp_poly
			(pts
				(xy -4.36372 -1.608328) (xy -4.36372 -2.233168) (xy -3.81 -1.905)
			)
			(stroke
				(width 0)
				(type default)
			)
			(fill yes)
			(layer "F.Fab")
		)
		(pad "1" smd rect
			(at -2.921 -1.949958 270)
			(size 0.3556 1.4986)
			(layers "F.Cu" "F.Mask" "F.Paste")
			(net "JTAG_BMC_SW_R_OE")
		)
		(pad "2" smd rect
			(at -2.921 -1.299972 270)
			(size 0.3556 1.4986)
			(layers "F.Cu" "F.Mask" "F.Paste")
			(net "JTAG_BMC_TCK_R")
		)
		(pad "3" smd rect
			(at -2.921 -0.649986 270)
			(size 0.3556 1.4986)
			(layers "F.Cu" "F.Mask" "F.Paste")
			(net "JTAG_BMC_SW_TCK_R")
		)
		(pad "4" smd rect
			(at -2.921 0 270)
			(size 0.3556 1.4986)
			(layers "F.Cu" "F.Mask" "F.Paste")
			(net "JTAG_BMC_SW_R_OE")
		)
		(pad "5" smd rect
			(at -2.921 0.649986 270)
			(size 0.3556 1.4986)
			(layers "F.Cu" "F.Mask" "F.Paste")
			(net "JTAG_BMC_TMS_R")
		)
		(pad "6" smd rect
			(at -2.921 1.299972 270)
			(size 0.3556 1.4986)
			(layers "F.Cu" "F.Mask" "F.Paste")
			(net "JTAG_BMC_SW_TMS_R")
		)
		(pad "7" smd rect
			(at -2.921 1.949958 270)
			(size 0.3556 1.4986)
			(layers "F.Cu" "F.Mask" "F.Paste")
			(net "GND")
		)
		(pad "8" smd rect
			(at 2.921 1.949958 270)
			(size 0.3556 1.4986)
			(layers "F.Cu" "F.Mask" "F.Paste")
			(net "JTAG_BMC_SW_TDI_R")
		)
		(pad "9" smd rect
			(at 2.921 1.299972 270)
			(size 0.3556 1.4986)
			(layers "F.Cu" "F.Mask" "F.Paste")
			(net "JTAG_BMC_TDI_R")
		)
		(pad "10" smd rect
			(at 2.921 0.649986 270)
			(size 0.3556 1.4986)
			(layers "F.Cu" "F.Mask" "F.Paste")
			(net "JTAG_BMC_SW_R_OE")
		)
		(pad "11" smd rect
			(at 2.921 0 270)
			(size 0.3556 1.4986)
			(layers "F.Cu" "F.Mask" "F.Paste")
			(net "JTAG_BMC_SW_TDO_R")
		)
		(pad "12" smd rect
			(at 2.921 -0.649986 270)
			(size 0.3556 1.4986)
			(layers "F.Cu" "F.Mask" "F.Paste")
			(net "JTAG_BMC_TDO_R")
		)
		(pad "13" smd rect
			(at 2.921 -1.299972 270)
			(size 0.3556 1.4986)
			(layers "F.Cu" "F.Mask" "F.Paste")
			(net "JTAG_BMC_SW_R_OE")
		)
		(pad "14" smd rect
			(at 2.921 -1.949958 270)
			(size 0.3556 1.4986)
			(layers "F.Cu" "F.Mask" "F.Paste")
			(net "P3V3_AUX")
		)
	)
	(footprint ""
		(layer "F.Cu")
		(at 236.649768 -192.499996)
		(property "Reference" "H94"
			(at -4.87172 -5.123688 0)
			(unlocked yes)
			(layer "F.SilkS")
			(effects
				(font
					(size 0.7874 0.5842)
					(thickness 0.1524)
				)
				(justify left)
			)
		)
		(property "Value" ""
			(at 0 0 0)
			(layer "F.Fab")
			(effects
				(font
					(size 1.27 1.27)
				)
			)
		)
		(duplicate_pad_numbers_are_jumpers no)
		(pad "1" thru_hole circle
			(at 0 0)
			(size 10.0076 10.0076)
			(drill 5.6134)
			(layers "*.Cu" "*.Mask")
			(remove_unused_layers no)
			(net "GND")
			(clearance -1.9431)
		)
	)
)
